(kicad_pcb
	(version 20260206)
	(generator "pcbnew")
	(generator_version "10.0")
	(general
		(thickness 1.6)
		(legacy_teardrops no)
	)
	(paper "A4")
	(title_block
		(title "01162023_DA0F0TEBIF0_F0T_Expander_BD_F_brd_V02_OCP.brd")
		(comment 1 "Grand Teton / footprints 8725-8732 of 9728")
	)
	(layers
		(0 "F.Cu" signal "TOP")
		(4 "In1.Cu" signal "GND")
		(6 "In2.Cu" signal "VCC")
		(8 "In3.Cu" signal "VCC1")
		(10 "In4.Cu" signal "GND1")
		(12 "In5.Cu" signal "IN1")
		(14 "In6.Cu" signal "GND2")
		(16 "In7.Cu" signal "IN2")
		(18 "In8.Cu" signal "GND3")
		(20 "In9.Cu" signal "IN3")
		(22 "In10.Cu" signal "GND4")
		(24 "In11.Cu" signal "IN4")
		(26 "In12.Cu" signal "GND5")
		(28 "In13.Cu" signal "IN5")
		(30 "In14.Cu" signal "GND6")
		(32 "In15.Cu" signal "IN6")
		(34 "In16.Cu" signal "GND7")
		(2 "B.Cu" signal "BOTTOM")
		(9 "F.Adhes" user "F.Adhesive")
		(11 "B.Adhes" user "B.Adhesive")
		(13 "F.Paste" user "Package Geometry/Pastemask Top")
		(15 "B.Paste" user "Package Geometry/Pastemask Bottom")
		(5 "F.SilkS" user "Ref Des/Silkscreen Top")
		(7 "B.SilkS" user "Ref Des/Silkscreen Bottom")
		(1 "F.Mask" user "Board Geometry/Soldermask Top")
		(3 "B.Mask" user "Board Geometry/Soldermask Bottom")
		(17 "Dwgs.User" user "User.Drawings")
		(19 "Cmts.User" user "User.Comments")
		(21 "Eco1.User" user "User.Eco1")
		(23 "Eco2.User" user "User.Eco2")
		(25 "Edge.Cuts" user "Board Geometry/Outline")
		(27 "Margin" user)
		(31 "F.CrtYd" user "Package Geometry/Place Bound Top")
		(29 "B.CrtYd" user "Package Geometry/Place Bound Bottom")
		(35 "F.Fab" user "Ref Des/Assembly Top")
		(33 "B.Fab" user "Ref Des/Assembly Bottom")
	)
	(footprint ""
		(layer "B.Cu")
		(at 46.355 -301.0408)
		(property "Reference" "C3001"
			(at 0 0 0)
			(layer "B.SilkS")
			(hide yes)
			(effects
				(font
					(size 1.27 1.27)
				)
				(justify mirror)
			)
		)
		(property "Value" ""
			(at 0 0 0)
			(layer "B.Fab")
			(effects
				(font
					(size 1.27 1.27)
				)
				(justify mirror)
			)
		)
		(duplicate_pad_numbers_are_jumpers no)
		(fp_line
			(start -0.299974 -0.150114)
			(end -0.299974 0.150114)
			(stroke
				(width 0.1)
				(type default)
			)
			(layer "B.Fab")
		)
		(fp_line
			(start -0.299974 0.150114)
			(end 0.299974 0.150114)
			(stroke
				(width 0.1)
				(type default)
			)
			(layer "B.Fab")
		)
		(fp_line
			(start 0.299974 -0.150114)
			(end -0.299974 -0.150114)
			(stroke
				(width 0.1)
				(type default)
			)
			(layer "B.Fab")
		)
		(fp_line
			(start 0.299974 0.150114)
			(end 0.299974 -0.150114)
			(stroke
				(width 0.1)
				(type default)
			)
			(layer "B.Fab")
		)
		(pad "1" smd rect
			(at 0.2667 0 180)
			(size 0.3048 0.381)
			(layers "B.Cu" "B.Mask" "B.Paste")
			(net "P1V8_PEX")
		)
		(pad "2" smd rect
			(at -0.2667 0 180)
			(size 0.3048 0.381)
			(layers "B.Cu" "B.Mask" "B.Paste")
			(net "GND")
		)
	)
	(footprint ""
		(layer "B.Cu")
		(at 116.788184 -316.868048 180)
		(property "Reference" "C4210"
			(at 0 0 0)
			(layer "B.SilkS")
			(hide yes)
			(effects
				(font
					(size 1.27 1.27)
				)
				(justify mirror)
			)
		)
		(property "Value" ""
			(at 0 0 0)
			(layer "B.Fab")
			(effects
				(font
					(size 1.27 1.27)
				)
				(justify mirror)
			)
		)
		(duplicate_pad_numbers_are_jumpers no)
		(fp_line
			(start 0.299974 0.150114)
			(end 0.299974 -0.150114)
			(stroke
				(width 0.1)
				(type default)
			)
			(layer "B.Fab")
		)
		(fp_line
			(start 0.299974 -0.150114)
			(end -0.299974 -0.150114)
			(stroke
				(width 0.1)
				(type default)
			)
			(layer "B.Fab")
		)
		(fp_line
			(start -0.299974 0.150114)
			(end 0.299974 0.150114)
			(stroke
				(width 0.1)
				(type default)
			)
			(layer "B.Fab")
		)
		(fp_line
			(start -0.299974 -0.150114)
			(end -0.299974 0.150114)
			(stroke
				(width 0.1)
				(type default)
			)
			(layer "B.Fab")
		)
		(pad "1" smd rect
			(at 0.2667 0)
			(size 0.3048 0.381)
			(layers "B.Cu" "B.Mask" "B.Paste")
			(net "P0V8_SERDES_VDDA_PEX0")
		)
		(pad "2" smd rect
			(at -0.2667 0)
			(size 0.3048 0.381)
			(layers "B.Cu" "B.Mask" "B.Paste")
			(net "GND")
		)
	)
	(footprint ""
		(layer "B.Cu")
		(at 342.09355 -221.98711 90)
		(property "Reference" "C2036"
			(at 0 0 90)
			(layer "B.SilkS")
			(hide yes)
			(effects
				(font
					(size 1.27 1.27)
				)
				(justify mirror)
			)
		)
		(property "Value" ""
			(at 0 0 90)
			(layer "B.Fab")
			(effects
				(font
					(size 1.27 1.27)
				)
				(justify mirror)
			)
		)
		(duplicate_pad_numbers_are_jumpers no)
		(fp_line
			(start 0.69215 -0.2921)
			(end -0.69215 -0.2921)
			(stroke
				(width 0.1524)
				(type default)
			)
			(layer "B.SilkS")
		)
		(fp_line
			(start -0.69215 -0.2921)
			(end -0.69215 0.2921)
			(stroke
				(width 0.1524)
				(type default)
			)
			(layer "B.SilkS")
		)
		(fp_line
			(start 0.69215 0.2921)
			(end 0.69215 -0.2921)
			(stroke
				(width 0.1524)
				(type default)
			)
			(layer "B.SilkS")
		)
		(fp_line
			(start -0.69215 0.2921)
			(end 0.69215 0.2921)
			(stroke
				(width 0.1524)
				(type default)
			)
			(layer "B.SilkS")
		)
		(fp_line
			(start 0.51435 -0.2794)
			(end -0.51435 -0.2794)
			(stroke
				(width 0.1)
				(type default)
			)
			(layer "B.Fab")
		)
		(fp_line
			(start -0.51435 -0.2794)
			(end -0.51435 0.2794)
			(stroke
				(width 0.1)
				(type default)
			)
			(layer "B.Fab")
		)
		(fp_line
			(start 0.51435 0.2794)
			(end 0.51435 -0.2794)
			(stroke
				(width 0.1)
				(type default)
			)
			(layer "B.Fab")
		)
		(fp_line
			(start -0.51435 0.2794)
			(end 0.51435 0.2794)
			(stroke
				(width 0.1)
				(type default)
			)
			(layer "B.Fab")
		)
		(pad "1" smd circle
			(at 0.40005 0 270)
			(size 0 0)
			(layers "B.Cu" "B.Mask" "B.Paste")
			(net "P3V3_FPGA_VCCIO0")
		)
		(pad "2" smd circle
			(at -0.40005 0 270)
			(size 0 0)
			(layers "B.Cu" "B.Mask" "B.Paste")
			(net "GND")
		)
		(zone
			(layer "B.Cu")
			(hatch none 0.5)
			(connect_pads
				(clearance 0)
			)
			(min_thickness 0.25)
			(keepout
				(tracks not_allowed)
				(vias allowed)
				(pads allowed)
				(copperpour not_allowed)
				(footprints allowed)
			)
			(placement
				(enabled no)
				(sheetname "")
			)
			(fill
				(thermal_gap 0.5)
				(thermal_bridge_width 0.5)
				(island_removal_mode 0)
			)
			(polygon
				(pts
					(xy 342.18118 -222.17761) (xy 342.239346 -222.08617) (xy 342.239346 -221.88678) (xy 342.18118 -221.79661)
					(xy 342.00592 -221.79661) (xy 341.9475 -221.88678) (xy 341.9475 -222.08617) (xy 342.005666 -222.17761)
				)
			)
		)
	)
	(footprint ""
		(layer "B.Cu")
		(at 224.005394 -444.94831 180)
		(property "Reference" "X77"
			(at 0.1778 -1.92913 180)
			(unlocked yes)
			(layer "B.SilkS")
			(effects
				(font
					(size 0.7874 0.5842)
					(thickness 0.1524)
				)
				(justify left mirror)
			)
		)
		(property "Value" ""
			(at 0 0 0)
			(layer "B.Fab")
			(effects
				(font
					(size 1.27 1.27)
				)
				(justify mirror)
			)
		)
		(property "Device Type" "TP_TDR_4P_FTS_MPKT4_H025P0200_IO_TP15_TP_TDR_4P_DIP"
			(at -1.30175 1.27 90)
			(unlocked yes)
			(layer "B.Fab")
			(hide yes)
			(effects
				(font
					(size 0.635 0.4064)
					(thickness 0.1524)
				)
				(justify mirror)
			)
		)
		(property "User Part Number" "TP15"
			(at -1.30175 1.27 90)
			(unlocked yes)
			(layer "Cmts.User")
			(hide yes)
			(effects
				(font
					(size 0.635 0.4064)
					(thickness 0.1524)
				)
				(justify mirror)
			)
		)
		(duplicate_pad_numbers_are_jumpers no)
		(fp_line
			(start 0 3.81)
			(end -2.54 3.81)
			(stroke
				(width 0.1524)
				(type default)
			)
			(layer "B.SilkS")
		)
		(fp_line
			(start 0 3.175)
			(end 0 3.81)
			(stroke
				(width 0.1524)
				(type default)
			)
			(layer "B.SilkS")
		)
		(fp_line
			(start 0 0.635)
			(end 0 1.905)
			(stroke
				(width 0.1524)
				(type default)
			)
			(layer "B.SilkS")
		)
		(fp_line
			(start 0 -1.27)
			(end 0 -0.635)
			(stroke
				(width 0.1524)
				(type default)
			)
			(layer "B.SilkS")
		)
		(fp_line
			(start -2.54 3.81)
			(end -2.54 3.6703)
			(stroke
				(width 0.1524)
				(type default)
			)
			(layer "B.SilkS")
		)
		(fp_line
			(start -2.54 1.4097)
			(end -2.54 1.1303)
			(stroke
				(width 0.1524)
				(type default)
			)
			(layer "B.SilkS")
		)
		(fp_line
			(start -2.54 -1.1303)
			(end -2.54 -1.27)
			(stroke
				(width 0.1524)
				(type default)
			)
			(layer "B.SilkS")
		)
		(fp_line
			(start -2.54 -1.27)
			(end 0 -1.27)
			(stroke
				(width 0.1524)
				(type default)
			)
			(layer "B.SilkS")
		)
		(fp_poly
			(pts
				(xy 0.761746 0) (xy 2.285746 -0.762) (xy 2.285746 0.762)
			)
			(stroke
				(width 0)
				(type default)
			)
			(fill yes)
			(layer "B.SilkS")
		)
		(fp_line
			(start 0 3.81)
			(end -2.54 3.81)
			(stroke
				(width 0.1)
				(type default)
			)
			(layer "B.Fab")
		)
		(fp_line
			(start 0 -1.27)
			(end 0 3.81)
			(stroke
				(width 0.1)
				(type default)
			)
			(layer "B.Fab")
		)
		(fp_line
			(start -2.54 3.81)
			(end -2.54 -1.27)
			(stroke
				(width 0.1)
				(type default)
			)
			(layer "B.Fab")
		)
		(fp_line
			(start -2.54 -1.27)
			(end 0 -1.27)
			(stroke
				(width 0.1)
				(type default)
			)
			(layer "B.Fab")
		)
		(fp_poly
			(pts
				(xy 0.761746 0) (xy 2.285746 -0.762) (xy 2.285746 0.762)
			)
			(stroke
				(width 0)
				(type default)
			)
			(fill yes)
			(layer "B.Fab")
		)
		(pad "1" thru_hole circle
			(at 0 0)
			(size 1.0033 1.0033)
			(drill 0.249936)
			(layers "*.Cu" "*.Mask")
			(remove_unused_layers no)
			(net "TDR_DIFF_100_IN5_DIN")
			(clearance 0.10795)
			(padstack
				(mode front_inner_back)
				(layer "Inner"
					(shape circle)
					(size 0.8001 0.8001)
					(clearance 0.1524)
				)
				(layer "B.Cu"
					(shape circle)
					(size 1.0033 1.0033)
					(thermal_gap 0.10795)
					(clearance 0.10795)
				)
			)
		)
		(pad "2" thru_hole circle
			(at -2.54 0)
			(size 1.9939 1.9939)
			(drill 0.249936)
			(layers "*.Cu" "*.Mask")
			(remove_unused_layers no)
			(net "COUPON_GND1")
			(clearance 0.10795)
			(padstack
				(mode front_inner_back)
				(layer "Inner"
					(shape circle)
					(size 0.8001 0.8001)
					(clearance 0.1524)
				)
				(layer "B.Cu"
					(shape circle)
					(size 1.9939 1.9939)
					(thermal_gap 0.10795)
					(clearance 0.10795)
				)
			)
		)
		(pad "3" thru_hole circle
			(at -2.54 2.54)
			(size 1.9939 1.9939)
			(drill 0.249936)
			(layers "*.Cu" "*.Mask")
			(remove_unused_layers no)
			(net "COUPON_GND1")
			(clearance 0.10795)
			(padstack
				(mode front_inner_back)
				(layer "Inner"
					(shape circle)
					(size 0.8001 0.8001)
					(clearance 0.1524)
				)
				(layer "B.Cu"
					(shape circle)
					(size 1.9939 1.9939)
					(thermal_gap 0.10795)
					(clearance 0.10795)
				)
			)
		)
		(pad "4" thru_hole circle
			(at 0 2.54)
			(size 1.0033 1.0033)
			(drill 0.249936)
			(layers "*.Cu" "*.Mask")
			(remove_unused_layers no)
			(net "TDR_DIFF_100_IN5_DIP")
			(clearance 0.10795)
			(padstack
				(mode front_inner_back)
				(layer "Inner"
					(shape circle)
					(size 0.8001 0.8001)
					(clearance 0.1524)
				)
				(layer "B.Cu"
					(shape circle)
					(size 1.0033 1.0033)
					(thermal_gap 0.10795)
					(clearance 0.10795)
				)
			)
		)
	)
	(footprint ""
		(layer "B.Cu")
		(at 125.357128 -285.600648 -90)
		(property "Reference" "PR7178"
			(at 0 0 90)
			(layer "B.SilkS")
			(hide yes)
			(effects
				(font
					(size 1.27 1.27)
				)
				(justify mirror)
			)
		)
		(property "Value" ""
			(at 0 0 90)
			(layer "B.Fab")
			(effects
				(font
					(size 1.27 1.27)
				)
				(justify mirror)
			)
		)
		(duplicate_pad_numbers_are_jumpers no)
		(fp_line
			(start -0.7874 0.4064)
			(end 0.7874 0.4064)
			(stroke
				(width 0.1524)
				(type default)
			)
			(layer "B.SilkS")
		)
		(fp_line
			(start 0.7874 0.4064)
			(end 0.7874 -0.4064)
			(stroke
				(width 0.1524)
				(type default)
			)
			(layer "B.SilkS")
		)
		(fp_line
			(start -0.7874 -0.4064)
			(end -0.7874 0.4064)
			(stroke
				(width 0.1524)
				(type default)
			)
			(layer "B.SilkS")
		)
		(fp_line
			(start 0.7874 -0.4064)
			(end -0.7874 -0.4064)
			(stroke
				(width 0.1524)
				(type default)
			)
			(layer "B.SilkS")
		)
		(fp_line
			(start -0.67945 0.3048)
			(end -0.120396 0.3048)
			(stroke
				(width 0.1)
				(type default)
			)
			(layer "B.Fab")
		)
		(fp_line
			(start -0.120396 0.3048)
			(end -0.120396 0.2794)
			(stroke
				(width 0.1)
				(type default)
			)
			(layer "B.Fab")
		)
		(fp_line
			(start 0.12065 0.3048)
			(end 0.67945 0.3048)
			(stroke
				(width 0.1)
				(type default)
			)
			(layer "B.Fab")
		)
		(fp_line
			(start 0.67945 0.3048)
			(end 0.67945 -0.305054)
			(stroke
				(width 0.1)
				(type default)
			)
			(layer "B.Fab")
		)
		(fp_line
			(start -0.120396 0.2794)
			(end 0.12065 0.2794)
			(stroke
				(width 0.1)
				(type default)
			)
			(layer "B.Fab")
		)
		(fp_line
			(start 0.12065 0.2794)
			(end 0.12065 0.3048)
			(stroke
				(width 0.1)
				(type default)
			)
			(layer "B.Fab")
		)
		(fp_line
			(start -0.12065 -0.2794)
			(end -0.12065 -0.3048)
			(stroke
				(width 0.1)
				(type default)
			)
			(layer "B.Fab")
		)
		(fp_line
			(start 0.12065 -0.2794)
			(end -0.12065 -0.2794)
			(stroke
				(width 0.1)
				(type default)
			)
			(layer "B.Fab")
		)
		(fp_line
			(start -0.67945 -0.3048)
			(end -0.67945 0.3048)
			(stroke
				(width 0.1)
				(type default)
			)
			(layer "B.Fab")
		)
		(fp_line
			(start -0.12065 -0.3048)
			(end -0.67945 -0.3048)
			(stroke
				(width 0.1)
				(type default)
			)
			(layer "B.Fab")
		)
		(fp_line
			(start 0.12065 -0.305054)
			(end 0.12065 -0.2794)
			(stroke
				(width 0.1)
				(type default)
			)
			(layer "B.Fab")
		)
		(fp_line
			(start 0.67945 -0.305054)
			(end 0.12065 -0.305054)
			(stroke
				(width 0.1)
				(type default)
			)
			(layer "B.Fab")
		)
		(pad "1" smd circle
			(at 0.40005 0 90)
			(size 0 0)
			(layers "B.Cu" "B.Mask" "B.Paste")
			(net "P0V8_PEX1_PVCC")
		)
		(pad "2" smd circle
			(at -0.40005 0 90)
			(size 0 0)
			(layers "B.Cu" "B.Mask" "B.Paste")
			(net "P5V_AUX")
		)
	)
	(footprint ""
		(layer "B.Cu")
		(at 425.841922 -103.104696 180)
		(property "Reference" "R373"
			(at 0 0 0)
			(layer "B.SilkS")
			(hide yes)
			(effects
				(font
					(size 1.27 1.27)
				)
				(justify mirror)
			)
		)
		(property "Value" ""
			(at 0 0 0)
			(layer "B.Fab")
			(effects
				(font
					(size 1.27 1.27)
				)
				(justify mirror)
			)
		)
		(duplicate_pad_numbers_are_jumpers no)
		(fp_line
			(start 0.7874 0.4064)
			(end 0.7874 -0.4064)
			(stroke
				(width 0.1524)
				(type default)
			)
			(layer "B.SilkS")
		)
		(fp_line
			(start 0.7874 -0.4064)
			(end -0.7874 -0.4064)
			(stroke
				(width 0.1524)
				(type default)
			)
			(layer "B.SilkS")
		)
		(fp_line
			(start -0.7874 0.4064)
			(end 0.7874 0.4064)
			(stroke
				(width 0.1524)
				(type default)
			)
			(layer "B.SilkS")
		)
		(fp_line
			(start -0.7874 -0.4064)
			(end -0.7874 0.4064)
			(stroke
				(width 0.1524)
				(type default)
			)
			(layer "B.SilkS")
		)
		(fp_line
			(start 0.67945 0.3048)
			(end 0.67945 -0.305054)
			(stroke
				(width 0.1)
				(type default)
			)
			(layer "B.Fab")
		)
		(fp_line
			(start 0.67945 -0.305054)
			(end 0.12065 -0.305054)
			(stroke
				(width 0.1)
				(type default)
			)
			(layer "B.Fab")
		)
		(fp_line
			(start 0.12065 0.3048)
			(end 0.67945 0.3048)
			(stroke
				(width 0.1)
				(type default)
			)
			(layer "B.Fab")
		)
		(fp_line
			(start 0.12065 0.2794)
			(end 0.12065 0.3048)
			(stroke
				(width 0.1)
				(type default)
			)
			(layer "B.Fab")
		)
		(fp_line
			(start 0.12065 -0.2794)
			(end -0.12065 -0.2794)
			(stroke
				(width 0.1)
				(type default)
			)
			(layer "B.Fab")
		)
		(fp_line
			(start 0.12065 -0.305054)
			(end 0.12065 -0.2794)
			(stroke
				(width 0.1)
				(type default)
			)
			(layer "B.Fab")
		)
		(fp_line
			(start -0.120396 0.3048)
			(end -0.120396 0.2794)
			(stroke
				(width 0.1)
				(type default)
			)
			(layer "B.Fab")
		)
		(fp_line
			(start -0.120396 0.2794)
			(end 0.12065 0.2794)
			(stroke
				(width 0.1)
				(type default)
			)
			(layer "B.Fab")
		)
		(fp_line
			(start -0.12065 -0.2794)
			(end -0.12065 -0.3048)
			(stroke
				(width 0.1)
				(type default)
			)
			(layer "B.Fab")
		)
		(fp_line
			(start -0.12065 -0.3048)
			(end -0.67945 -0.3048)
			(stroke
				(width 0.1)
				(type default)
			)
			(layer "B.Fab")
		)
		(fp_line
			(start -0.67945 0.3048)
			(end -0.120396 0.3048)
			(stroke
				(width 0.1)
				(type default)
			)
			(layer "B.Fab")
		)
		(fp_line
			(start -0.67945 -0.3048)
			(end -0.67945 0.3048)
			(stroke
				(width 0.1)
				(type default)
			)
			(layer "B.Fab")
		)
		(pad "1" smd circle
			(at 0.40005 0)
			(size 0 0)
			(layers "B.Cu" "B.Mask" "B.Paste")
			(net "NCSI_NIC7_RXD0")
		)
		(pad "2" smd circle
			(at -0.40005 0)
			(size 0 0)
			(layers "B.Cu" "B.Mask" "B.Paste")
			(net "GND")
		)
	)
	(footprint ""
		(layer "B.Cu")
		(at 70.099936 -290.674806 180)
		(property "Reference" "C2994"
			(at 0 0 0)
			(layer "B.SilkS")
			(hide yes)
			(effects
				(font
					(size 1.27 1.27)
				)
				(justify mirror)
			)
		)
		(property "Value" ""
			(at 0 0 0)
			(layer "B.Fab")
			(effects
				(font
					(size 1.27 1.27)
				)
				(justify mirror)
			)
		)
		(duplicate_pad_numbers_are_jumpers no)
		(fp_line
			(start 0.299974 0.150114)
			(end 0.299974 -0.150114)
			(stroke
				(width 0.1)
				(type default)
			)
			(layer "B.Fab")
		)
		(fp_line
			(start 0.299974 -0.150114)
			(end -0.299974 -0.150114)
			(stroke
				(width 0.1)
				(type default)
			)
			(layer "B.Fab")
		)
		(fp_line
			(start -0.299974 0.150114)
			(end 0.299974 0.150114)
			(stroke
				(width 0.1)
				(type default)
			)
			(layer "B.Fab")
		)
		(fp_line
			(start -0.299974 -0.150114)
			(end -0.299974 0.150114)
			(stroke
				(width 0.1)
				(type default)
			)
			(layer "B.Fab")
		)
		(pad "1" smd rect
			(at 0.2667 0)
			(size 0.3048 0.381)
			(layers "B.Cu" "B.Mask" "B.Paste")
			(net "P1V8_PEX")
		)
		(pad "2" smd rect
			(at -0.2667 0)
			(size 0.3048 0.381)
			(layers "B.Cu" "B.Mask" "B.Paste")
			(net "GND")
		)
	)
	(footprint ""
		(layer "B.Cu")
		(at 443.802262 -457.938886 90)
		(property "Reference" "J49"
			(at 3.5052 -5.552948 90)
			(unlocked yes)
			(layer "B.SilkS")
			(effects
				(font
					(size 0.7874 0.5842)
					(thickness 0.1524)
				)
				(justify left mirror)
			)
		)
		(property "Value" ""
			(at 0 0 90)
			(layer "B.Fab")
			(effects
				(font
					(size 1.27 1.27)
				)
				(justify mirror)
			)
		)
		(duplicate_pad_numbers_are_jumpers no)
		(fp_line
			(start 3.330702 -4.771136)
			(end -3.330702 -4.771136)
			(stroke
				(width 0.1524)
				(type default)
			)
			(layer "B.SilkS")
		)
		(fp_line
			(start -3.330702 -4.771136)
			(end 0 4.011168)
			(stroke
				(width 0.1524)
				(type default)
			)
			(layer "B.SilkS")
		)
		(fp_line
			(start 0 4.011168)
			(end 3.330702 -4.771136)
			(stroke
				(width 0.1524)
				(type default)
			)
			(layer "B.SilkS")
		)
		(fp_line
			(start 3.330702 -4.771136)
			(end -3.330702 -4.771136)
			(stroke
				(width 0.1)
				(type default)
			)
			(layer "B.Fab")
		)
		(fp_line
			(start -3.330702 -4.771136)
			(end 0 4.011168)
			(stroke
				(width 0.1)
				(type default)
			)
			(layer "B.Fab")
		)
		(fp_line
			(start 0 4.011168)
			(end 3.330702 -4.771136)
			(stroke
				(width 0.1)
				(type default)
			)
			(layer "B.Fab")
		)
		(pad "1" thru_hole circle
			(at 0 0 270)
			(size 2.159 2.159)
			(drill 1.7018)
			(layers "*.Cu" "*.Mask")
			(remove_unused_layers no)
			(net "COUPON_GND1")
			(clearance 0.0254)
			(thermal_gap 0.0254)
		)
		(pad "2" thru_hole circle
			(at 1.27 -3.348736 270)
			(size 2.159 2.159)
			(drill 1.7018)
			(layers "*.Cu" "*.Mask")
			(remove_unused_layers no)
			(net "TDR_SE_50_OHM_IN3")
			(clearance 0.0254)
			(thermal_gap 0.0254)
		)
		(pad "3" thru_hole circle
			(at -1.27 -3.348736 270)
			(size 2.159 2.159)
			(drill 1.7018)
			(layers "*.Cu" "*.Mask")
			(remove_unused_layers no)
			(net "TDR_SE_50_OHM_IN3")
			(clearance 0.0254)
			(thermal_gap 0.0254)
		)
	)
)
